(kicad_sch
	(version 20250114)
	(generator "eeschema")
	(generator_version "9.0")
	(paper "A3")
	(title_block
		(title "Thunderbolt to 10GbE adapter")
		(date "2026-04-23")
		(rev "1.1.0")
		(company "Antmicro Ltd")
		(comment 1 "www.antmicro.com")
	)
	(text "SPI Flash For Thunderbolt"
		(exclude_from_sim no)
		(at 220.98 114.3 0)
		(effects
			(font
				(size 2.54 2.54)
				(thickness 0.508)
				(bold yes)
			)
		)
	)
	(text "Support 150-mils and 200-mils package"
		(exclude_from_sim no)
		(at 200.66 170.18 0)
		(effects
			(font
				(size 1.27 1.27)
			)
			(justify left bottom)
		)
	)
	(junction
		(at 185.42 130.81)
		(diameter 0)
		(color 0 0 0 0)
	)
	(junction
		(at 147.32 121.92)
		(diameter 0)
		(color 0 0 0 0)
	)
	(junction
		(at 219.71 151.13)
		(diameter 0)
		(color 0 0 0 0)
	)
	(junction
		(at 252.73 135.89)
		(diameter 0)
		(color 0 0 0 0)
	)
	(junction
		(at 219.71 160.02)
		(diameter 0)
		(color 0 0 0 0)
	)
	(junction
		(at 259.08 135.89)
		(diameter 0)
		(color 0 0 0 0)
	)
	(junction
		(at 265.43 135.89)
		(diameter 0)
		(color 0 0 0 0)
	)
	(junction
		(at 271.78 162.56)
		(diameter 0)
		(color 0 0 0 0)
	)
	(junction
		(at 252.73 152.4)
		(diameter 0)
		(color 0 0 0 0)
	)
	(bus_entry
		(at 147.32 151.13)
		(size 1.27 1.27)
		(stroke
			(width 0)
			(type default)
		)
	)
	(bus_entry
		(at 147.32 148.59)
		(size 1.27 1.27)
		(stroke
			(width 0)
			(type default)
		)
	)
	(bus_entry
		(at 147.32 161.29)
		(size 1.27 1.27)
		(stroke
			(width 0)
			(type default)
		)
	)
	(bus_entry
		(at 292.1 161.29)
		(size -1.27 1.27)
		(stroke
			(width 0)
			(type default)
		)
	)
	(bus_entry
		(at 292.1 151.13)
		(size -1.27 1.27)
		(stroke
			(width 0)
			(type default)
		)
	)
	(bus_entry
		(at 292.1 158.75)
		(size -1.27 1.27)
		(stroke
			(width 0)
			(type default)
		)
	)
	(bus_entry
		(at 292.1 148.59)
		(size -1.27 1.27)
		(stroke
			(width 0)
			(type default)
		)
	)
	(bus_entry
		(at 147.32 158.75)
		(size 1.27 1.27)
		(stroke
			(width 0)
			(type default)
		)
	)
	(wire
		(pts
			(xy 271.78 162.56) (xy 290.83 162.56)
		)
		(stroke
			(width 0)
			(type default)
		)
	)
	(wire
		(pts
			(xy 252.73 152.4) (xy 290.83 152.4)
		)
		(stroke
			(width 0)
			(type default)
		)
	)
	(wire
		(pts
			(xy 217.17 160.02) (xy 219.71 160.02)
		)
		(stroke
			(width 0)
			(type default)
		)
	)
	(bus
		(pts
			(xy 147.32 158.75) (xy 147.32 161.29)
		)
		(stroke
			(width 0)
			(type default)
		)
	)
	(wire
		(pts
			(xy 185.42 130.81) (xy 219.71 130.81)
		)
		(stroke
			(width 0)
			(type default)
		)
	)
	(wire
		(pts
			(xy 148.59 152.4) (xy 191.77 152.4)
		)
		(stroke
			(width 0)
			(type default)
		)
	)
	(wire
		(pts
			(xy 148.59 160.02) (xy 191.77 160.02)
		)
		(stroke
			(width 0)
			(type default)
		)
	)
	(wire
		(pts
			(xy 271.78 135.89) (xy 271.78 138.43)
		)
		(stroke
			(width 0)
			(type default)
		)
	)
	(bus
		(pts
			(xy 147.32 148.59) (xy 147.32 151.13)
		)
		(stroke
			(width 0)
			(type default)
		)
	)
	(bus
		(pts
			(xy 292.1 151.13) (xy 292.1 158.75)
		)
		(stroke
			(width 0)
			(type default)
		)
	)
	(wire
		(pts
			(xy 252.73 135.89) (xy 252.73 138.43)
		)
		(stroke
			(width 0)
			(type default)
		)
	)
	(wire
		(pts
			(xy 259.08 135.89) (xy 265.43 135.89)
		)
		(stroke
			(width 0)
			(type default)
		)
	)
	(wire
		(pts
			(xy 247.65 160.02) (xy 290.83 160.02)
		)
		(stroke
			(width 0)
			(type default)
		)
	)
	(wire
		(pts
			(xy 247.65 149.86) (xy 290.83 149.86)
		)
		(stroke
			(width 0)
			(type default)
		)
	)
	(wire
		(pts
			(xy 265.43 143.51) (xy 265.43 157.48)
		)
		(stroke
			(width 0)
			(type default)
		)
	)
	(bus
		(pts
			(xy 140.97 121.92) (xy 147.32 121.92)
		)
		(stroke
			(width 0)
			(type default)
		)
	)
	(wire
		(pts
			(xy 173.99 157.48) (xy 191.77 157.48)
		)
		(stroke
			(width 0)
			(type default)
		)
	)
	(wire
		(pts
			(xy 219.71 151.13) (xy 222.25 151.13)
		)
		(stroke
			(width 0)
			(type default)
		)
	)
	(wire
		(pts
			(xy 185.42 137.16) (xy 185.42 138.43)
		)
		(stroke
			(width 0)
			(type default)
		)
	)
	(wire
		(pts
			(xy 247.65 162.56) (xy 271.78 162.56)
		)
		(stroke
			(width 0)
			(type default)
		)
	)
	(wire
		(pts
			(xy 191.77 154.94) (xy 167.64 154.94)
		)
		(stroke
			(width 0)
			(type default)
		)
	)
	(wire
		(pts
			(xy 252.73 134.62) (xy 252.73 135.89)
		)
		(stroke
			(width 0)
			(type default)
		)
	)
	(wire
		(pts
			(xy 219.71 160.02) (xy 219.71 162.56)
		)
		(stroke
			(width 0)
			(type default)
		)
	)
	(wire
		(pts
			(xy 259.08 143.51) (xy 259.08 154.94)
		)
		(stroke
			(width 0)
			(type default)
		)
	)
	(bus
		(pts
			(xy 147.32 151.13) (xy 147.32 158.75)
		)
		(stroke
			(width 0)
			(type default)
		)
	)
	(bus
		(pts
			(xy 289.56 121.92) (xy 292.1 124.46)
		)
		(stroke
			(width 0)
			(type default)
		)
	)
	(wire
		(pts
			(xy 252.73 135.89) (xy 259.08 135.89)
		)
		(stroke
			(width 0)
			(type default)
		)
	)
	(wire
		(pts
			(xy 185.42 130.81) (xy 185.42 132.08)
		)
		(stroke
			(width 0)
			(type default)
		)
	)
	(wire
		(pts
			(xy 247.65 157.48) (xy 265.43 157.48)
		)
		(stroke
			(width 0)
			(type default)
		)
	)
	(wire
		(pts
			(xy 252.73 143.51) (xy 252.73 152.4)
		)
		(stroke
			(width 0)
			(type default)
		)
	)
	(wire
		(pts
			(xy 219.71 160.02) (xy 222.25 160.02)
		)
		(stroke
			(width 0)
			(type default)
		)
	)
	(wire
		(pts
			(xy 148.59 149.86) (xy 191.77 149.86)
		)
		(stroke
			(width 0)
			(type default)
		)
	)
	(wire
		(pts
			(xy 247.65 152.4) (xy 252.73 152.4)
		)
		(stroke
			(width 0)
			(type default)
		)
	)
	(wire
		(pts
			(xy 265.43 135.89) (xy 265.43 138.43)
		)
		(stroke
			(width 0)
			(type default)
		)
	)
	(wire
		(pts
			(xy 217.17 151.13) (xy 219.71 151.13)
		)
		(stroke
			(width 0)
			(type default)
		)
	)
	(wire
		(pts
			(xy 271.78 143.51) (xy 271.78 162.56)
		)
		(stroke
			(width 0)
			(type default)
		)
	)
	(bus
		(pts
			(xy 147.32 121.92) (xy 289.56 121.92)
		)
		(stroke
			(width 0)
			(type default)
		)
	)
	(wire
		(pts
			(xy 185.42 129.54) (xy 185.42 130.81)
		)
		(stroke
			(width 0)
			(type default)
		)
	)
	(wire
		(pts
			(xy 219.71 130.81) (xy 219.71 151.13)
		)
		(stroke
			(width 0)
			(type default)
		)
	)
	(bus
		(pts
			(xy 147.32 148.59) (xy 147.32 121.92)
		)
		(stroke
			(width 0)
			(type default)
		)
	)
	(wire
		(pts
			(xy 259.08 135.89) (xy 259.08 138.43)
		)
		(stroke
			(width 0)
			(type default)
		)
	)
	(wire
		(pts
			(xy 265.43 135.89) (xy 271.78 135.89)
		)
		(stroke
			(width 0)
			(type default)
		)
	)
	(bus
		(pts
			(xy 292.1 124.46) (xy 292.1 148.59)
		)
		(stroke
			(width 0)
			(type default)
		)
	)
	(wire
		(pts
			(xy 247.65 154.94) (xy 259.08 154.94)
		)
		(stroke
			(width 0)
			(type default)
		)
	)
	(bus
		(pts
			(xy 292.1 158.75) (xy 292.1 161.29)
		)
		(stroke
			(width 0)
			(type default)
		)
	)
	(bus
		(pts
			(xy 292.1 148.59) (xy 292.1 151.13)
		)
		(stroke
			(width 0)
			(type default)
		)
	)
	(wire
		(pts
			(xy 148.59 162.56) (xy 191.77 162.56)
		)
		(stroke
			(width 0)
			(type default)
		)
	)
	(label "TB_FLASH.MOSI"
		(at 173.99 149.86 0)
		(effects
			(font
				(size 1.27 1.27)
			)
			(justify left bottom)
		)
	)
	(label "TB_FLASH.~{CE}"
		(at 290.83 162.56 180)
		(effects
			(font
				(size 1.27 1.27)
			)
			(justify right bottom)
		)
	)
	(label "TB_FLASH.~{CE}"
		(at 173.99 162.56 0)
		(effects
			(font
				(size 1.27 1.27)
			)
			(justify left bottom)
		)
	)
	(label "FLASH_WP"
		(at 248.92 154.94 0)
		(effects
			(font
				(size 1.27 1.27)
			)
			(justify left bottom)
		)
	)
	(label "TB_FLASH.MISO"
		(at 173.99 152.4 0)
		(effects
			(font
				(size 1.27 1.27)
			)
			(justify left bottom)
		)
	)
	(label "FLASH_HOLD"
		(at 248.92 157.48 0)
		(effects
			(font
				(size 1.27 1.27)
			)
			(justify left bottom)
		)
	)
	(label "TB_FLASH.MOSI"
		(at 290.83 149.86 180)
		(effects
			(font
				(size 1.27 1.27)
			)
			(justify right bottom)
		)
	)
	(label "TB_FLASH.CLK"
		(at 290.83 160.02 180)
		(effects
			(font
				(size 1.27 1.27)
			)
			(justify right bottom)
		)
	)
	(label "FLASH_HOLD"
		(at 173.99 157.48 0)
		(effects
			(font
				(size 1.27 1.27)
			)
			(justify left bottom)
		)
	)
	(label "TB_FLASH.MISO"
		(at 290.83 152.4 180)
		(effects
			(font
				(size 1.27 1.27)
			)
			(justify right bottom)
		)
	)
	(label "FLASH_WP"
		(at 173.99 154.94 0)
		(effects
			(font
				(size 1.27 1.27)
			)
			(justify left bottom)
		)
	)
	(label "TB_FLASH.CLK"
		(at 173.99 160.02 0)
		(effects
			(font
				(size 1.27 1.27)
			)
			(justify left bottom)
		)
	)
	(hierarchical_label "FLASH_WP"
		(shape input)
		(at 167.64 154.94 180)
		(effects
			(font
				(size 1.27 1.27)
			)
			(justify right)
		)
	)
	(hierarchical_label "TB_FLASH{SPI}"
		(shape bidirectional)
		(at 140.97 121.92 180)
		(effects
			(font
				(size 1.27 1.27)
			)
			(justify right)
		)
	)
	(symbol
		(lib_id "antmicropower:GND")
		(at 219.71 162.56 0)
		(unit 1)
		(exclude_from_sim no)
		(in_bom yes)
		(on_board yes)
		(dnp no)
		(property "Reference" "#PWR0145"
			(at 219.71 168.91 0)
			(effects
				(font
					(size 1.27 1.27)
				)
				(hide yes)
			)
		)
		(property "Value" "GND"
			(at 219.71 166.37 0)
			(effects
				(font
					(size 1.27 1.27)
				)
			)
		)
		(property "Footprint" ""
			(at 219.71 162.56 0)
			(effects
				(font
					(size 1.27 1.27)
				)
				(hide yes)
			)
		)
		(property "Datasheet" ""
			(at 219.71 162.56 0)
			(effects
				(font
					(size 1.27 1.27)
				)
				(hide yes)
			)
		)
		(property "Description" ""
			(at 219.71 162.56 0)
			(effects
				(font
					(size 1.27 1.27)
				)
				(hide yes)
			)
		)
		(property "Author" "Antmicro"
			(at 228.6 170.18 0)
			(effects
				(font
					(size 1.27 1.27)
					(thickness 0.15)
				)
				(justify left bottom)
				(hide yes)
			)
		)
		(property "License" "Apache-2.0"
			(at 228.6 172.72 0)
			(effects
				(font
					(size 1.27 1.27)
					(thickness 0.15)
				)
				(justify left bottom)
				(hide yes)
			)
		)
		(pin "1"
		)
		(instances
			(project "thunderbolt-to-10gbe-adapter"
				(path ""
					(reference "#PWR0145")
					(unit 1)
				)
			)
		)
	)
	(symbol
		(lib_id "antmicroResistors0402:R_3k3_0402")
		(at 252.73 143.51 270)
		(mirror x)
		(unit 1)
		(exclude_from_sim no)
		(in_bom yes)
		(on_board yes)
		(dnp no)
		(property "Reference" "R79"
			(at 251.714 139.7 90)
			(effects
				(font
					(size 1.27 1.27)
					(thickness 0.15)
				)
				(justify right)
			)
		)
		(property "Value" "R_3k3_0402"
			(at 240.03 123.19 0)
			(effects
				(font
					(size 1.27 1.27)
					(thickness 0.15)
				)
				(justify left bottom)
				(hide yes)
			)
		)
		(property "Footprint" "antmicro-footprints:R_0402_1005Metric"
			(at 237.49 123.19 0)
			(effects
				(font
					(size 1.27 1.27)
					(thickness 0.15)
				)
				(justify left bottom)
				(hide yes)
			)
		)
		(property "Datasheet" "https://www.bourns.com/docs/product-datasheets/cr.pdf"
			(at 234.95 123.19 0)
			(effects
				(font
					(size 1.27 1.27)
					(thickness 0.15)
				)
				(justify left bottom)
				(hide yes)
			)
		)
		(property "Description" "SMD Chip Resistor, 3.3 kohm, ± 1%, 63 mW, 0402 [1005 Metric], Thick Film, General Purpose"
			(at 252.73 143.51 0)
			(effects
				(font
					(size 1.27 1.27)
				)
				(hide yes)
			)
		)
		(property "MPN" "CR0402-FX-3301GLF"
			(at 232.41 123.19 0)
			(effects
				(font
					(size 1.27 1.27)
					(thickness 0.15)
				)
				(justify left bottom)
				(hide yes)
			)
		)
		(property "Manufacturer" "Bourns"
			(at 229.87 123.19 0)
			(effects
				(font
					(size 1.27 1.27)
					(thickness 0.15)
				)
				(justify left bottom)
				(hide yes)
			)
		)
		(property "License" "Apache-2.0"
			(at 227.33 123.19 0)
			(effects
				(font
					(size 1.27 1.27)
					(thickness 0.15)
				)
				(justify left bottom)
				(hide yes)
			)
		)
		(property "Val" "3k3"
			(at 251.714 142.24 90)
			(effects
				(font
					(size 1.27 1.27)
					(thickness 0.15)
				)
				(justify right)
			)
		)
		(property "Tolerance" "1%"
			(at 242.57 123.19 0)
			(effects
				(font
					(size 1.27 1.27)
				)
				(justify left bottom)
				(hide yes)
			)
		)
		(property "Author" "Antmicro"
			(at 224.79 123.19 0)
			(effects
				(font
					(size 1.27 1.27)
					(thickness 0.15)
				)
				(justify left bottom)
				(hide yes)
			)
		)
		(pin "1"
		)
		(pin "2"
		)
		(instances
			(project "thunderbolt-to-10gbe-adapter"
				(path ""
					(reference "R79")
					(unit 1)
				)
			)
		)
	)
	(symbol
		(lib_id "antmicroMemory:MX25L8006EM1I-12G")
		(at 191.77 149.86 0)
		(unit 1)
		(exclude_from_sim no)
		(in_bom yes)
		(on_board yes)
		(dnp no)
		(property "Reference" "U7"
			(at 204.47 142.875 0)
			(effects
				(font
					(size 1.27 1.27)
					(thickness 0.15)
				)
			)
		)
		(property "Value" "MX25L8006EM1I-12G"
			(at 227.33 152.4 0)
			(effects
				(font
					(size 1.27 1.27)
					(thickness 0.15)
				)
				(justify left bottom)
				(hide yes)
			)
		)
		(property "Footprint" "antmicro-footprints:SOIC-8_3.9x4.9x1.75mm_P1.27mm"
			(at 227.33 154.94 0)
			(effects
				(font
					(size 1.27 1.27)
					(thickness 0.15)
				)
				(justify left bottom)
				(hide yes)
			)
		)
		(property "Datasheet" "https://www.macronix.com/Lists/Datasheet/Attachments/8680/MX25L8006E,%203V,%208Mb,%20v1.6.pdf"
			(at 227.33 157.48 0)
			(effects
				(font
					(size 1.27 1.27)
					(thickness 0.15)
				)
				(justify left bottom)
				(hide yes)
			)
		)
		(property "Description" "FLASH - NOR Memory IC 8Mbit SPI 86 MHz 8-SOP"
			(at 191.77 149.86 0)
			(effects
				(font
					(size 1.27 1.27)
				)
				(hide yes)
			)
		)
		(property "MPN" "MX25L8006EM1I-12G"
			(at 204.47 145.415 0)
			(effects
				(font
					(size 1.27 1.27)
					(thickness 0.15)
				)
			)
		)
		(property "Manufacturer" "Macronix"
			(at 227.33 162.56 0)
			(effects
				(font
					(size 1.27 1.27)
					(thickness 0.15)
				)
				(justify left bottom)
				(hide yes)
			)
		)
		(property "License" "Apache-2.0"
			(at 227.33 167.64 0)
			(effects
				(font
					(size 1.27 1.27)
					(thickness 0.15)
				)
				(justify left bottom)
				(hide yes)
			)
		)
		(property "Author" "Antmicro"
			(at 227.33 165.1 0)
			(effects
				(font
					(size 1.27 1.27)
					(thickness 0.15)
				)
				(justify left bottom)
				(hide yes)
			)
		)
		(pin "1"
		)
		(pin "2"
		)
		(pin "3"
		)
		(pin "4"
		)
		(pin "5"
		)
		(pin "6"
		)
		(pin "7"
		)
		(pin "8"
		)
		(instances
			(project "thunderbolt-to-10gbe-adapter"
				(path ""
					(reference "U7")
					(unit 1)
				)
			)
		)
	)
	(symbol
		(lib_id "antmicroResistors0402:R_3k3_0402")
		(at 259.08 143.51 270)
		(mirror x)
		(unit 1)
		(exclude_from_sim no)
		(in_bom yes)
		(on_board yes)
		(dnp no)
		(property "Reference" "R80"
			(at 258.064 139.7 90)
			(effects
				(font
					(size 1.27 1.27)
					(thickness 0.15)
				)
				(justify right)
			)
		)
		(property "Value" "R_3k3_0402"
			(at 246.38 123.19 0)
			(effects
				(font
					(size 1.27 1.27)
					(thickness 0.15)
				)
				(justify left bottom)
				(hide yes)
			)
		)
		(property "Footprint" "antmicro-footprints:R_0402_1005Metric"
			(at 243.84 123.19 0)
			(effects
				(font
					(size 1.27 1.27)
					(thickness 0.15)
				)
				(justify left bottom)
				(hide yes)
			)
		)
		(property "Datasheet" "https://www.bourns.com/docs/product-datasheets/cr.pdf"
			(at 241.3 123.19 0)
			(effects
				(font
					(size 1.27 1.27)
					(thickness 0.15)
				)
				(justify left bottom)
				(hide yes)
			)
		)
		(property "Description" "SMD Chip Resistor, 3.3 kohm, ± 1%, 63 mW, 0402 [1005 Metric], Thick Film, General Purpose"
			(at 259.08 143.51 0)
			(effects
				(font
					(size 1.27 1.27)
				)
				(hide yes)
			)
		)
		(property "MPN" "CR0402-FX-3301GLF"
			(at 238.76 123.19 0)
			(effects
				(font
					(size 1.27 1.27)
					(thickness 0.15)
				)
				(justify left bottom)
				(hide yes)
			)
		)
		(property "Manufacturer" "Bourns"
			(at 236.22 123.19 0)
			(effects
				(font
					(size 1.27 1.27)
					(thickness 0.15)
				)
				(justify left bottom)
				(hide yes)
			)
		)
		(property "License" "Apache-2.0"
			(at 233.68 123.19 0)
			(effects
				(font
					(size 1.27 1.27)
					(thickness 0.15)
				)
				(justify left bottom)
				(hide yes)
			)
		)
		(property "Val" "3k3"
			(at 258.064 142.24 90)
			(effects
				(font
					(size 1.27 1.27)
					(thickness 0.15)
				)
				(justify right)
			)
		)
		(property "Tolerance" "1%"
			(at 248.92 123.19 0)
			(effects
				(font
					(size 1.27 1.27)
				)
				(justify left bottom)
				(hide yes)
			)
		)
		(property "Author" "Antmicro"
			(at 231.14 123.19 0)
			(effects
				(font
					(size 1.27 1.27)
					(thickness 0.15)
				)
				(justify left bottom)
				(hide yes)
			)
		)
		(pin "1"
		)
		(pin "2"
		)
		(instances
			(project "thunderbolt-to-10gbe-adapter"
				(path ""
					(reference "R80")
					(unit 1)
				)
			)
		)
	)
	(symbol
		(lib_id "antmicropower:+3V3")
		(at 252.73 134.62 0)
		(unit 1)
		(exclude_from_sim no)
		(in_bom yes)
		(on_board yes)
		(dnp no)
		(property "Reference" "#PWR0146"
			(at 267.97 134.62 0)
			(effects
				(font
					(size 1.27 1.27)
					(thickness 0.15)
				)
				(justify left bottom)
				(hide yes)
			)
		)
		(property "Value" "+3V3_TB"
			(at 252.73 130.81 0)
			(effects
				(font
					(size 1.27 1.27)
					(thickness 0.15)
				)
			)
		)
		(property "Footprint" ""
			(at 267.97 142.24 0)
			(effects
				(font
					(size 1.27 1.27)
					(thickness 0.15)
				)
				(justify left bottom)
				(hide yes)
			)
		)
		(property "Datasheet" ""
			(at 267.97 144.78 0)
			(effects
				(font
					(size 1.27 1.27)
					(thickness 0.15)
				)
				(justify left bottom)
				(hide yes)
			)
		)
		(property "Description" ""
			(at 267.97 147.32 0)
			(effects
				(font
					(size 1.27 1.27)
				)
				(justify left bottom)
				(hide yes)
			)
		)
		(property "Author" "Antmicro"
			(at 267.97 137.16 0)
			(effects
				(font
					(size 1.27 1.27)
					(thickness 0.15)
				)
				(justify left bottom)
				(hide yes)
			)
		)
		(property "License" "Apache-2.0"
			(at 267.97 139.7 0)
			(effects
				(font
					(size 1.27 1.27)
					(thickness 0.15)
				)
				(justify left bottom)
				(hide yes)
			)
		)
		(pin "1"
		)
		(instances
			(project "thunderbolt-to-10gbe-adapter"
				(path ""
					(reference "#PWR0146")
					(unit 1)
				)
			)
		)
	)
	(symbol
		(lib_id "antmicroCapacitors0402:C_100n_0402")
		(at 185.42 137.16 270)
		(mirror x)
		(unit 1)
		(exclude_from_sim no)
		(in_bom yes)
		(on_board yes)
		(dnp no)
		(fields_autoplaced yes)
		(property "Reference" "C103"
			(at 182.88 133.3436 90)
			(effects
				(font
					(size 1.27 1.27)
					(thickness 0.15)
				)
				(justify right)
			)
		)
		(property "Value" "C_100n_0402"
			(at 175.26 116.84 0)
			(effects
				(font
					(size 1.27 1.27)
					(thickness 0.15)
				)
				(justify left bottom)
				(hide yes)
			)
		)
		(property "Footprint" "antmicro-footprints:C_0402_1005Metric"
			(at 172.72 116.84 0)
			(effects
				(font
					(size 1.27 1.27)
					(thickness 0.15)
				)
				(justify left bottom)
				(hide yes)
			)
		)
		(property "Datasheet" "https://www.murata.com/products/productdetail?partno=GRM155R61H104KE14%23"
			(at 170.18 116.84 0)
			(effects
				(font
					(size 1.27 1.27)
					(thickness 0.15)
				)
				(justify left bottom)
				(hide yes)
			)
		)
		(property "Description" "SMD Multilayer Ceramic Capacitor, 0.1 µF, 50 V, 0402 [1005 Metric], ± 10%, X5R, GRM Series"
			(at 185.42 137.16 0)
			(effects
				(font
					(size 1.27 1.27)
				)
				(hide yes)
			)
		)
		(property "MPN" "GRM155R61H104KE14D"
			(at 167.64 116.84 0)
			(effects
				(font
					(size 1.27 1.27)
					(thickness 0.15)
				)
				(justify left bottom)
				(hide yes)
			)
		)
		(property "Manufacturer" "Murata"
			(at 165.1 116.84 0)
			(effects
				(font
					(size 1.27 1.27)
					(thickness 0.15)
				)
				(justify left bottom)
				(hide yes)
			)
		)
		(property "License" "Apache-2.0"
			(at 162.56 116.84 0)
			(effects
				(font
					(size 1.27 1.27)
					(thickness 0.15)
				)
				(justify left bottom)
				(hide yes)
			)
		)
		(property "Val" "100n"
			(at 182.88 135.8836 90)
			(effects
				(font
					(size 1.27 1.27)
					(thickness 0.15)
				)
				(justify right)
			)
		)
		(property "Voltage" "50V"
			(at 157.48 116.84 0)
			(effects
				(font
					(size 1.27 1.27)
				)
				(justify left bottom)
				(hide yes)
			)
		)
		(property "Dielectric" "X5R"
			(at 154.94 116.84 0)
			(effects
				(font
					(size 1.27 1.27)
				)
				(justify left bottom)
				(hide yes)
			)
		)
		(property "Author" "Antmicro"
			(at 160.02 116.84 0)
			(effects
				(font
					(size 1.27 1.27)
					(thickness 0.15)
				)
				(justify left bottom)
				(hide yes)
			)
		)
		(pin "1"
		)
		(pin "2"
		)
		(instances
			(project "thunderbolt-to-10gbe-adapter"
				(path ""
					(reference "C103")
					(unit 1)
				)
			)
		)
	)
	(symbol
		(lib_id "antmicroMemory:MX25L8006EM2I-12G")
		(at 247.65 149.86 0)
		(mirror y)
		(unit 1)
		(exclude_from_sim no)
		(in_bom yes)
		(on_board yes)
		(dnp yes)
		(property "Reference" "U8"
			(at 234.95 142.875 0)
			(effects
				(font
					(size 1.27 1.27)
					(thickness 0.15)
				)
			)
		)
		(property "Value" "MX25L8006EM2I-12G"
			(at 212.09 152.4 0)
			(effects
				(font
					(size 1.27 1.27)
					(thickness 0.15)
				)
				(justify left bottom)
				(hide yes)
			)
		)
		(property "Footprint" "antmicro-footprints:SOIC-8_5.3x5.3x2mm_P1.27mm"
			(at 212.09 154.94 0)
			(effects
				(font
					(size 1.27 1.27)
					(thickness 0.15)
				)
				(justify left bottom)
				(hide yes)
			)
		)
		(property "Datasheet" "https://www.macronix.com/Lists/Datasheet/Attachments/8680/MX25L8006E,%203V,%208Mb,%20v1.6.pdf"
			(at 212.09 157.48 0)
			(effects
				(font
					(size 1.27 1.27)
					(thickness 0.15)
				)
				(justify left bottom)
				(hide yes)
			)
		)
		(property "Description" "FLASH - NOR Memory IC 8Mbit SPI 86 MHz 8-SOP"
			(at 247.65 149.86 0)
			(effects
				(font
					(size 1.27 1.27)
				)
				(hide yes)
			)
		)
		(property "MPN" "MX25L8006EM2I-12G"
			(at 234.95 145.415 0)
			(effects
				(font
					(size 1.27 1.27)
					(thickness 0.15)
				)
			)
		)
		(property "Manufacturer" "Macronix"
			(at 212.09 162.56 0)
			(effects
				(font
					(size 1.27 1.27)
					(thickness 0.15)
				)
				(justify left bottom)
				(hide yes)
			)
		)
		(property "Author" "Antmicro"
			(at 212.09 165.1 0)
			(effects
				(font
					(size 1.27 1.27)
					(thickness 0.15)
				)
				(justify left bottom)
				(hide yes)
			)
		)
		(property "License" "Apache-2.0"
			(at 212.09 167.64 0)
			(effects
				(font
					(size 1.27 1.27)
					(thickness 0.15)
				)
				(justify left bottom)
				(hide yes)
			)
		)
		(pin "1"
		)
		(pin "2"
		)
		(pin "3"
		)
		(pin "4"
		)
		(pin "5"
		)
		(pin "6"
		)
		(pin "7"
		)
		(pin "8"
		)
		(instances
			(project "thunderbolt-to-10gbe-adapter"
				(path ""
					(reference "U8")
					(unit 1)
				)
			)
		)
	)
	(symbol
		(lib_id "antmicropower:+3V3")
		(at 185.42 129.54 0)
		(unit 1)
		(exclude_from_sim no)
		(in_bom yes)
		(on_board yes)
		(dnp no)
		(property "Reference" "#PWR0143"
			(at 200.66 129.54 0)
			(effects
				(font
					(size 1.27 1.27)
					(thickness 0.15)
				)
				(justify left bottom)
				(hide yes)
			)
		)
		(property "Value" "+3V3_TB"
			(at 185.42 125.73 0)
			(effects
				(font
					(size 1.27 1.27)
					(thickness 0.15)
				)
			)
		)
		(property "Footprint" ""
			(at 200.66 137.16 0)
			(effects
				(font
					(size 1.27 1.27)
					(thickness 0.15)
				)
				(justify left bottom)
				(hide yes)
			)
		)
		(property "Datasheet" ""
			(at 200.66 139.7 0)
			(effects
				(font
					(size 1.27 1.27)
					(thickness 0.15)
				)
				(justify left bottom)
				(hide yes)
			)
		)
		(property "Description" ""
			(at 200.66 142.24 0)
			(effects
				(font
					(size 1.27 1.27)
				)
				(justify left bottom)
				(hide yes)
			)
		)
		(property "Author" "Antmicro"
			(at 200.66 132.08 0)
			(effects
				(font
					(size 1.27 1.27)
					(thickness 0.15)
				)
				(justify left bottom)
				(hide yes)
			)
		)
		(property "License" "Apache-2.0"
			(at 200.66 134.62 0)
			(effects
				(font
					(size 1.27 1.27)
					(thickness 0.15)
				)
				(justify left bottom)
				(hide yes)
			)
		)
		(pin "1"
		)
		(instances
			(project "thunderbolt-to-10gbe-adapter"
				(path ""
					(reference "#PWR0143")
					(unit 1)
				)
			)
		)
	)
	(symbol
		(lib_id "antmicroResistors0402:R_3k3_0402")
		(at 271.78 143.51 270)
		(mirror x)
		(unit 1)
		(exclude_from_sim no)
		(in_bom yes)
		(on_board yes)
		(dnp no)
		(property "Reference" "R82"
			(at 270.764 139.7 90)
			(effects
				(font
					(size 1.27 1.27)
					(thickness 0.15)
				)
				(justify right)
			)
		)
		(property "Value" "R_3k3_0402"
			(at 259.08 123.19 0)
			(effects
				(font
					(size 1.27 1.27)
					(thickness 0.15)
				)
				(justify left bottom)
				(hide yes)
			)
		)
		(property "Footprint" "antmicro-footprints:R_0402_1005Metric"
			(at 256.54 123.19 0)
			(effects
				(font
					(size 1.27 1.27)
					(thickness 0.15)
				)
				(justify left bottom)
				(hide yes)
			)
		)
		(property "Datasheet" "https://www.bourns.com/docs/product-datasheets/cr.pdf"
			(at 254 123.19 0)
			(effects
				(font
					(size 1.27 1.27)
					(thickness 0.15)
				)
				(justify left bottom)
				(hide yes)
			)
		)
		(property "Description" "SMD Chip Resistor, 3.3 kohm, ± 1%, 63 mW, 0402 [1005 Metric], Thick Film, General Purpose"
			(at 271.78 143.51 0)
			(effects
				(font
					(size 1.27 1.27)
				)
				(hide yes)
			)
		)
		(property "MPN" "CR0402-FX-3301GLF"
			(at 251.46 123.19 0)
			(effects
				(font
					(size 1.27 1.27)
					(thickness 0.15)
				)
				(justify left bottom)
				(hide yes)
			)
		)
		(property "Manufacturer" "Bourns"
			(at 248.92 123.19 0)
			(effects
				(font
					(size 1.27 1.27)
					(thickness 0.15)
				)
				(justify left bottom)
				(hide yes)
			)
		)
		(property "License" "Apache-2.0"
			(at 246.38 123.19 0)
			(effects
				(font
					(size 1.27 1.27)
					(thickness 0.15)
				)
				(justify left bottom)
				(hide yes)
			)
		)
		(property "Val" "3k3"
			(at 270.764 142.24 90)
			(effects
				(font
					(size 1.27 1.27)
					(thickness 0.15)
				)
				(justify right)
			)
		)
		(property "Tolerance" "1%"
			(at 261.62 123.19 0)
			(effects
				(font
					(size 1.27 1.27)
				)
				(justify left bottom)
				(hide yes)
			)
		)
		(property "Author" "Antmicro"
			(at 243.84 123.19 0)
			(effects
				(font
					(size 1.27 1.27)
					(thickness 0.15)
				)
				(justify left bottom)
				(hide yes)
			)
		)
		(pin "1"
		)
		(pin "2"
		)
		(instances
			(project "thunderbolt-to-10gbe-adapter"
				(path ""
					(reference "R82")
					(unit 1)
				)
			)
		)
	)
	(symbol
		(lib_id "antmicroResistors0402:R_3k3_0402")
		(at 265.43 138.43 90)
		(mirror x)
		(unit 1)
		(exclude_from_sim no)
		(in_bom yes)
		(on_board yes)
		(dnp no)
		(property "Reference" "R81"
			(at 264.414 139.7 90)
			(effects
				(font
					(size 1.27 1.27)
					(thickness 0.15)
				)
				(justify left)
			)
		)
		(property "Value" "R_3k3_0402"
			(at 278.13 158.75 0)
			(effects
				(font
					(size 1.27 1.27)
					(thickness 0.15)
				)
				(justify left bottom)
				(hide yes)
			)
		)
		(property "Footprint" "antmicro-footprints:R_0402_1005Metric"
			(at 280.67 158.75 0)
			(effects
				(font
					(size 1.27 1.27)
					(thickness 0.15)
				)
				(justify left bottom)
				(hide yes)
			)
		)
		(property "Datasheet" "https://www.bourns.com/docs/product-datasheets/cr.pdf"
			(at 283.21 158.75 0)
			(effects
				(font
					(size 1.27 1.27)
					(thickness 0.15)
				)
				(justify left bottom)
				(hide yes)
			)
		)
		(property "Description" "SMD Chip Resistor, 3.3 kohm, ± 1%, 63 mW, 0402 [1005 Metric], Thick Film, General Purpose"
			(at 265.43 138.43 0)
			(effects
				(font
					(size 1.27 1.27)
				)
				(hide yes)
			)
		)
		(property "MPN" "CR0402-FX-3301GLF"
			(at 285.75 158.75 0)
			(effects
				(font
					(size 1.27 1.27)
					(thickness 0.15)
				)
				(justify left bottom)
				(hide yes)
			)
		)
		(property "Manufacturer" "Bourns"
			(at 288.29 158.75 0)
			(effects
				(font
					(size 1.27 1.27)
					(thickness 0.15)
				)
				(justify left bottom)
				(hide yes)
			)
		)
		(property "License" "Apache-2.0"
			(at 290.83 158.75 0)
			(effects
				(font
					(size 1.27 1.27)
					(thickness 0.15)
				)
				(justify left bottom)
				(hide yes)
			)
		)
		(property "Val" "3k3"
			(at 264.414 142.24 90)
			(effects
				(font
					(size 1.27 1.27)
					(thickness 0.15)
				)
				(justify left)
			)
		)
		(property "Tolerance" "1%"
			(at 275.59 158.75 0)
			(effects
				(font
					(size 1.27 1.27)
				)
				(justify left bottom)
				(hide yes)
			)
		)
		(property "Author" "Antmicro"
			(at 293.37 158.75 0)
			(effects
				(font
					(size 1.27 1.27)
					(thickness 0.15)
				)
				(justify left bottom)
				(hide yes)
			)
		)
		(pin "1"
		)
		(pin "2"
		)
		(instances
			(project "thunderbolt-to-10gbe-adapter"
				(path ""
					(reference "R81")
					(unit 1)
				)
			)
		)
	)
	(symbol
		(lib_id "antmicropower:GND")
		(at 185.42 138.43 0)
		(unit 1)
		(exclude_from_sim no)
		(in_bom yes)
		(on_board yes)
		(dnp no)
		(property "Reference" "#PWR0144"
			(at 185.42 144.78 0)
			(effects
				(font
					(size 1.27 1.27)
				)
				(hide yes)
			)
		)
		(property "Value" "GND"
			(at 185.42 142.24 0)
			(effects
				(font
					(size 1.27 1.27)
				)
			)
		)
		(property "Footprint" ""
			(at 185.42 138.43 0)
			(effects
				(font
					(size 1.27 1.27)
				)
				(hide yes)
			)
		)
		(property "Datasheet" ""
			(at 185.42 138.43 0)
			(effects
				(font
					(size 1.27 1.27)
				)
				(hide yes)
			)
		)
		(property "Description" ""
			(at 185.42 138.43 0)
			(effects
				(font
					(size 1.27 1.27)
				)
				(hide yes)
			)
		)
		(property "Author" "Antmicro"
			(at 194.31 146.05 0)
			(effects
				(font
					(size 1.27 1.27)
					(thickness 0.15)
				)
				(justify left bottom)
				(hide yes)
			)
		)
		(property "License" "Apache-2.0"
			(at 194.31 148.59 0)
			(effects
				(font
					(size 1.27 1.27)
					(thickness 0.15)
				)
				(justify left bottom)
				(hide yes)
			)
		)
		(pin "1"
		)
		(instances
			(project "thunderbolt-to-10gbe-adapter"
				(path ""
					(reference "#PWR0144")
					(unit 1)
				)
			)
		)
	)
)
